(kicad_pcb
	(version 20260206)
	(generator "pcbnew")
	(generator_version "10.0")
	(general
		(thickness 1.6)
		(legacy_teardrops no)
	)
	(paper "A4")
	(title_block
		(title "12092022_DA0F0TFB6D0_F0T_FAN_BOARD_MP5048_D_brd_v02_OCP.brd")
		(comment 1 "Grand Teton / footprints 658-663 of 924")
	)
	(layers
		(0 "F.Cu" signal "TOP")
		(4 "In1.Cu" signal "GND")
		(6 "In2.Cu" signal "IN1")
		(8 "In3.Cu" signal "IN2")
		(10 "In4.Cu" signal "GND1")
		(2 "B.Cu" signal "BOTTOM")
		(9 "F.Adhes" user "F.Adhesive")
		(11 "B.Adhes" user "B.Adhesive")
		(13 "F.Paste" user "Package Geometry/Pastemask Top")
		(15 "B.Paste" user "Package Geometry/Pastemask Bottom")
		(5 "F.SilkS" user "Ref Des/Silkscreen Top")
		(7 "B.SilkS" user "Ref Des/Silkscreen Bottom")
		(1 "F.Mask" user "Board Geometry/Soldermask Top")
		(3 "B.Mask" user "Board Geometry/Soldermask Bottom")
		(17 "Dwgs.User" user "User.Drawings")
		(19 "Cmts.User" user "User.Comments")
		(21 "Eco1.User" user "User.Eco1")
		(23 "Eco2.User" user "User.Eco2")
		(25 "Edge.Cuts" user "Board Geometry/Outline")
		(27 "Margin" user)
		(31 "F.CrtYd" user "Package Geometry/Place Bound Top")
		(29 "B.CrtYd" user "Package Geometry/Place Bound Bottom")
		(35 "F.Fab" user "Ref Des/Assembly Top")
		(33 "B.Fab" user "Ref Des/Assembly Bottom")
	)
	(footprint ""
		(layer "F.Cu")
		(at 43.942 -311.277 -90)
		(property "Reference" "Q9"
			(at 2.77495 0.7874 0)
			(unlocked yes)
			(layer "F.SilkS")
			(effects
				(font
					(size 0.7874 0.5842)
					(thickness 0.1524)
				)
				(justify left)
			)
		)
		(property "Value" ""
			(at 0 0 270)
			(layer "F.Fab")
			(effects
				(font
					(size 1.27 1.27)
				)
			)
		)
		(duplicate_pad_numbers_are_jumpers no)
		(fp_line
			(start -1.905 1.651)
			(end -1.905 -1.651)
			(stroke
				(width 0.1524)
				(type default)
			)
			(layer "F.SilkS")
		)
		(fp_line
			(start 1.905 1.651)
			(end -1.905 1.651)
			(stroke
				(width 0.1524)
				(type default)
			)
			(layer "F.SilkS")
		)
		(fp_line
			(start -1.905 -1.651)
			(end 1.905 -1.651)
			(stroke
				(width 0.1524)
				(type default)
			)
			(layer "F.SilkS")
		)
		(fp_line
			(start 1.905 -1.651)
			(end 1.905 1.651)
			(stroke
				(width 0.1524)
				(type default)
			)
			(layer "F.SilkS")
		)
		(fp_line
			(start -0.6985 1.524)
			(end -0.6985 1.169924)
			(stroke
				(width 0.1)
				(type default)
			)
			(layer "F.Fab")
		)
		(fp_line
			(start 0.6985 1.524)
			(end -0.6985 1.524)
			(stroke
				(width 0.1)
				(type default)
			)
			(layer "F.Fab")
		)
		(fp_line
			(start -1.249934 1.169924)
			(end -1.249934 0.729996)
			(stroke
				(width 0.1)
				(type default)
			)
			(layer "F.Fab")
		)
		(fp_line
			(start -0.6985 1.169924)
			(end -1.249934 1.169924)
			(stroke
				(width 0.1)
				(type default)
			)
			(layer "F.Fab")
		)
		(fp_line
			(start -1.249934 0.729996)
			(end -0.6985 0.729996)
			(stroke
				(width 0.1)
				(type default)
			)
			(layer "F.Fab")
		)
		(fp_line
			(start -0.6985 0.729996)
			(end -0.6985 -0.729996)
			(stroke
				(width 0.1)
				(type default)
			)
			(layer "F.Fab")
		)
		(fp_line
			(start 0.6985 0.219964)
			(end 0.6985 1.524)
			(stroke
				(width 0.1)
				(type default)
			)
			(layer "F.Fab")
		)
		(fp_line
			(start 1.249934 0.219964)
			(end 0.6985 0.219964)
			(stroke
				(width 0.1)
				(type default)
			)
			(layer "F.Fab")
		)
		(fp_line
			(start 0.6985 -0.219964)
			(end 1.249934 -0.219964)
			(stroke
				(width 0.1)
				(type default)
			)
			(layer "F.Fab")
		)
		(fp_line
			(start 1.249934 -0.219964)
			(end 1.249934 0.219964)
			(stroke
				(width 0.1)
				(type default)
			)
			(layer "F.Fab")
		)
		(fp_line
			(start -1.249934 -0.729996)
			(end -1.249934 -1.169924)
			(stroke
				(width 0.1)
				(type default)
			)
			(layer "F.Fab")
		)
		(fp_line
			(start -0.6985 -0.729996)
			(end -1.249934 -0.729996)
			(stroke
				(width 0.1)
				(type default)
			)
			(layer "F.Fab")
		)
		(fp_line
			(start -1.249934 -1.169924)
			(end -0.6985 -1.169924)
			(stroke
				(width 0.1)
				(type default)
			)
			(layer "F.Fab")
		)
		(fp_line
			(start -0.6985 -1.169924)
			(end -0.6985 -1.524)
			(stroke
				(width 0.1)
				(type default)
			)
			(layer "F.Fab")
		)
		(fp_line
			(start -0.6985 -1.524)
			(end 0.6985 -1.524)
			(stroke
				(width 0.1)
				(type default)
			)
			(layer "F.Fab")
		)
		(fp_line
			(start 0.6985 -1.524)
			(end 0.6985 -0.219964)
			(stroke
				(width 0.1)
				(type default)
			)
			(layer "F.Fab")
		)
		(fp_rect
			(start -0.6985 1.524)
			(end 0.6985 -1.524)
			(stroke
				(width 0)
				(type default)
			)
			(fill no)
			(layer "F.Fab")
		)
		(pad "D" smd rect
			(at 1.1176 0 180)
			(size 1.016 1.27)
			(layers "F.Cu" "F.Mask" "F.Paste")
			(net "P12V_LED_FAN0")
		)
		(pad "G" smd rect
			(at -1.1176 -1.016 180)
			(size 1.016 1.27)
			(layers "F.Cu" "F.Mask" "F.Paste")
			(net "U405_D1")
		)
		(pad "S" smd rect
			(at -1.1176 1.016 180)
			(size 1.016 1.27)
			(layers "F.Cu" "F.Mask" "F.Paste")
			(net "P12V_LED")
		)
	)
	(footprint ""
		(layer "F.Cu")
		(at 38.6461 -132.588)
		(property "Reference" "R5577"
			(at 0 0 0)
			(layer "F.SilkS")
			(hide yes)
			(effects
				(font
					(size 1.27 1.27)
				)
			)
		)
		(property "Value" ""
			(at 0 0 0)
			(layer "F.Fab")
			(effects
				(font
					(size 1.27 1.27)
				)
			)
		)
		(duplicate_pad_numbers_are_jumpers no)
		(fp_line
			(start -0.7874 -0.4064)
			(end 0.7874 -0.4064)
			(stroke
				(width 0.1524)
				(type default)
			)
			(layer "F.SilkS")
		)
		(fp_line
			(start -0.7874 0.4064)
			(end -0.7874 -0.4064)
			(stroke
				(width 0.1524)
				(type default)
			)
			(layer "F.SilkS")
		)
		(fp_line
			(start 0.7874 -0.4064)
			(end 0.7874 0.4064)
			(stroke
				(width 0.1524)
				(type default)
			)
			(layer "F.SilkS")
		)
		(fp_line
			(start 0.7874 0.4064)
			(end -0.7874 0.4064)
			(stroke
				(width 0.1524)
				(type default)
			)
			(layer "F.SilkS")
		)
		(fp_line
			(start -0.67945 -0.305054)
			(end -0.12065 -0.305054)
			(stroke
				(width 0.1)
				(type default)
			)
			(layer "F.Fab")
		)
		(fp_line
			(start -0.67945 0.3048)
			(end -0.67945 -0.305054)
			(stroke
				(width 0.1)
				(type default)
			)
			(layer "F.Fab")
		)
		(fp_line
			(start -0.12065 -0.305054)
			(end -0.12065 -0.2794)
			(stroke
				(width 0.1)
				(type default)
			)
			(layer "F.Fab")
		)
		(fp_line
			(start -0.12065 -0.2794)
			(end 0.12065 -0.2794)
			(stroke
				(width 0.1)
				(type default)
			)
			(layer "F.Fab")
		)
		(fp_line
			(start -0.12065 0.2794)
			(end -0.12065 0.3048)
			(stroke
				(width 0.1)
				(type default)
			)
			(layer "F.Fab")
		)
		(fp_line
			(start -0.12065 0.3048)
			(end -0.67945 0.3048)
			(stroke
				(width 0.1)
				(type default)
			)
			(layer "F.Fab")
		)
		(fp_line
			(start 0.120396 0.2794)
			(end -0.12065 0.2794)
			(stroke
				(width 0.1)
				(type default)
			)
			(layer "F.Fab")
		)
		(fp_line
			(start 0.120396 0.3048)
			(end 0.120396 0.2794)
			(stroke
				(width 0.1)
				(type default)
			)
			(layer "F.Fab")
		)
		(fp_line
			(start 0.12065 -0.3048)
			(end 0.67945 -0.3048)
			(stroke
				(width 0.1)
				(type default)
			)
			(layer "F.Fab")
		)
		(fp_line
			(start 0.12065 -0.2794)
			(end 0.12065 -0.3048)
			(stroke
				(width 0.1)
				(type default)
			)
			(layer "F.Fab")
		)
		(fp_line
			(start 0.67945 -0.3048)
			(end 0.67945 0.3048)
			(stroke
				(width 0.1)
				(type default)
			)
			(layer "F.Fab")
		)
		(fp_line
			(start 0.67945 0.3048)
			(end 0.120396 0.3048)
			(stroke
				(width 0.1)
				(type default)
			)
			(layer "F.Fab")
		)
		(pad "1" smd rect
			(at -0.40005 0 180)
			(size 0.4572 0.508)
			(layers "F.Cu" "F.Mask" "F.Paste")
			(net "FAN_1_PWM")
		)
		(pad "2" smd rect
			(at 0.40005 0 180)
			(size 0.4572 0.508)
			(layers "F.Cu" "F.Mask" "F.Paste")
			(net "FAN_1_PWM_R2")
		)
	)
	(footprint ""
		(layer "F.Cu")
		(at 23.622 -133.985 90)
		(property "Reference" "R4947"
			(at 0 0 90)
			(layer "F.SilkS")
			(hide yes)
			(effects
				(font
					(size 1.27 1.27)
				)
			)
		)
		(property "Value" ""
			(at 0 0 90)
			(layer "F.Fab")
			(effects
				(font
					(size 1.27 1.27)
				)
			)
		)
		(duplicate_pad_numbers_are_jumpers no)
		(fp_line
			(start 0.7874 -0.4064)
			(end 0.7874 0.4064)
			(stroke
				(width 0.1524)
				(type default)
			)
			(layer "F.SilkS")
		)
		(fp_line
			(start -0.7874 -0.4064)
			(end 0.7874 -0.4064)
			(stroke
				(width 0.1524)
				(type default)
			)
			(layer "F.SilkS")
		)
		(fp_line
			(start 0.7874 0.4064)
			(end -0.7874 0.4064)
			(stroke
				(width 0.1524)
				(type default)
			)
			(layer "F.SilkS")
		)
		(fp_line
			(start -0.7874 0.4064)
			(end -0.7874 -0.4064)
			(stroke
				(width 0.1524)
				(type default)
			)
			(layer "F.SilkS")
		)
		(fp_line
			(start -0.12065 -0.305054)
			(end -0.12065 -0.2794)
			(stroke
				(width 0.1)
				(type default)
			)
			(layer "F.Fab")
		)
		(fp_line
			(start -0.67945 -0.305054)
			(end -0.12065 -0.305054)
			(stroke
				(width 0.1)
				(type default)
			)
			(layer "F.Fab")
		)
		(fp_line
			(start 0.67945 -0.3048)
			(end 0.67945 0.3048)
			(stroke
				(width 0.1)
				(type default)
			)
			(layer "F.Fab")
		)
		(fp_line
			(start 0.12065 -0.3048)
			(end 0.67945 -0.3048)
			(stroke
				(width 0.1)
				(type default)
			)
			(layer "F.Fab")
		)
		(fp_line
			(start 0.12065 -0.2794)
			(end 0.12065 -0.3048)
			(stroke
				(width 0.1)
				(type default)
			)
			(layer "F.Fab")
		)
		(fp_line
			(start -0.12065 -0.2794)
			(end 0.12065 -0.2794)
			(stroke
				(width 0.1)
				(type default)
			)
			(layer "F.Fab")
		)
		(fp_line
			(start 0.120396 0.2794)
			(end -0.12065 0.2794)
			(stroke
				(width 0.1)
				(type default)
			)
			(layer "F.Fab")
		)
		(fp_line
			(start -0.12065 0.2794)
			(end -0.12065 0.3048)
			(stroke
				(width 0.1)
				(type default)
			)
			(layer "F.Fab")
		)
		(fp_line
			(start 0.67945 0.3048)
			(end 0.120396 0.3048)
			(stroke
				(width 0.1)
				(type default)
			)
			(layer "F.Fab")
		)
		(fp_line
			(start 0.120396 0.3048)
			(end 0.120396 0.2794)
			(stroke
				(width 0.1)
				(type default)
			)
			(layer "F.Fab")
		)
		(fp_line
			(start -0.12065 0.3048)
			(end -0.67945 0.3048)
			(stroke
				(width 0.1)
				(type default)
			)
			(layer "F.Fab")
		)
		(fp_line
			(start -0.67945 0.3048)
			(end -0.67945 -0.305054)
			(stroke
				(width 0.1)
				(type default)
			)
			(layer "F.Fab")
		)
		(pad "1" smd circle
			(at -0.40005 0 90)
			(size 0 0)
			(layers "F.Cu" "F.Mask" "F.Paste")
			(net "MAX31790_U330_FREQ_START")
		)
		(pad "2" smd circle
			(at 0.40005 0 90)
			(size 0 0)
			(layers "F.Cu" "F.Mask" "F.Paste")
			(net "P3V3_AUX")
		)
	)
	(footprint ""
		(layer "F.Cu")
		(at 3.937 -312.674 -90)
		(property "Reference" "U412"
			(at 1.32588 2.00787 90)
			(unlocked yes)
			(layer "F.SilkS")
			(effects
				(font
					(size 0.7874 0.5842)
					(thickness 0.1524)
				)
				(justify left)
			)
		)
		(property "Value" ""
			(at 0 0 270)
			(layer "F.Fab")
			(effects
				(font
					(size 1.27 1.27)
				)
			)
		)
		(duplicate_pad_numbers_are_jumpers no)
		(fp_line
			(start -1.335278 1.100074)
			(end 1.335278 1.100074)
			(stroke
				(width 0.1524)
				(type default)
			)
			(layer "F.SilkS")
		)
		(fp_line
			(start 1.335278 1.100074)
			(end 1.335278 -1.100074)
			(stroke
				(width 0.1524)
				(type default)
			)
			(layer "F.SilkS")
		)
		(fp_line
			(start -1.335278 -1.100074)
			(end -1.335278 1.100074)
			(stroke
				(width 0.1524)
				(type default)
			)
			(layer "F.SilkS")
		)
		(fp_line
			(start 1.335278 -1.100074)
			(end -1.335278 -1.100074)
			(stroke
				(width 0.1524)
				(type default)
			)
			(layer "F.SilkS")
		)
		(fp_line
			(start -0.674878 1.100074)
			(end 0.674878 1.100074)
			(stroke
				(width 0.1)
				(type default)
			)
			(layer "F.Fab")
		)
		(fp_line
			(start 0.674878 1.100074)
			(end 0.674878 -1.100074)
			(stroke
				(width 0.1)
				(type default)
			)
			(layer "F.Fab")
		)
		(fp_line
			(start -0.674878 -1.100074)
			(end -0.674878 1.100074)
			(stroke
				(width 0.1)
				(type default)
			)
			(layer "F.Fab")
		)
		(fp_line
			(start 0.674878 -1.100074)
			(end -0.674878 -1.100074)
			(stroke
				(width 0.1)
				(type default)
			)
			(layer "F.Fab")
		)
		(pad "D" smd rect
			(at 0.8001 0 180)
			(size 0.6096 0.8128)
			(layers "F.Cu" "F.Mask" "F.Paste")
			(net "U412_D1")
		)
		(pad "G" smd rect
			(at -0.8001 -0.649986 180)
			(size 0.6096 0.8128)
			(layers "F.Cu" "F.Mask" "F.Paste")
			(net "FAN_7_PRESENT")
		)
		(pad "S" smd rect
			(at -0.8001 0.649986 180)
			(size 0.6096 0.8128)
			(layers "F.Cu" "F.Mask" "F.Paste")
			(net "GND")
		)
	)
	(footprint ""
		(layer "F.Cu")
		(at 38.6461 -136.398)
		(property "Reference" "R5574"
			(at 0 0 0)
			(layer "F.SilkS")
			(hide yes)
			(effects
				(font
					(size 1.27 1.27)
				)
			)
		)
		(property "Value" ""
			(at 0 0 0)
			(layer "F.Fab")
			(effects
				(font
					(size 1.27 1.27)
				)
			)
		)
		(duplicate_pad_numbers_are_jumpers no)
		(fp_line
			(start -0.7874 -0.4064)
			(end 0.7874 -0.4064)
			(stroke
				(width 0.1524)
				(type default)
			)
			(layer "F.SilkS")
		)
		(fp_line
			(start -0.7874 0.4064)
			(end -0.7874 -0.4064)
			(stroke
				(width 0.1524)
				(type default)
			)
			(layer "F.SilkS")
		)
		(fp_line
			(start 0.7874 -0.4064)
			(end 0.7874 0.4064)
			(stroke
				(width 0.1524)
				(type default)
			)
			(layer "F.SilkS")
		)
		(fp_line
			(start 0.7874 0.4064)
			(end -0.7874 0.4064)
			(stroke
				(width 0.1524)
				(type default)
			)
			(layer "F.SilkS")
		)
		(fp_line
			(start -0.67945 -0.305054)
			(end -0.12065 -0.305054)
			(stroke
				(width 0.1)
				(type default)
			)
			(layer "F.Fab")
		)
		(fp_line
			(start -0.67945 0.3048)
			(end -0.67945 -0.305054)
			(stroke
				(width 0.1)
				(type default)
			)
			(layer "F.Fab")
		)
		(fp_line
			(start -0.12065 -0.305054)
			(end -0.12065 -0.2794)
			(stroke
				(width 0.1)
				(type default)
			)
			(layer "F.Fab")
		)
		(fp_line
			(start -0.12065 -0.2794)
			(end 0.12065 -0.2794)
			(stroke
				(width 0.1)
				(type default)
			)
			(layer "F.Fab")
		)
		(fp_line
			(start -0.12065 0.2794)
			(end -0.12065 0.3048)
			(stroke
				(width 0.1)
				(type default)
			)
			(layer "F.Fab")
		)
		(fp_line
			(start -0.12065 0.3048)
			(end -0.67945 0.3048)
			(stroke
				(width 0.1)
				(type default)
			)
			(layer "F.Fab")
		)
		(fp_line
			(start 0.120396 0.2794)
			(end -0.12065 0.2794)
			(stroke
				(width 0.1)
				(type default)
			)
			(layer "F.Fab")
		)
		(fp_line
			(start 0.120396 0.3048)
			(end 0.120396 0.2794)
			(stroke
				(width 0.1)
				(type default)
			)
			(layer "F.Fab")
		)
		(fp_line
			(start 0.12065 -0.3048)
			(end 0.67945 -0.3048)
			(stroke
				(width 0.1)
				(type default)
			)
			(layer "F.Fab")
		)
		(fp_line
			(start 0.12065 -0.2794)
			(end 0.12065 -0.3048)
			(stroke
				(width 0.1)
				(type default)
			)
			(layer "F.Fab")
		)
		(fp_line
			(start 0.67945 -0.3048)
			(end 0.67945 0.3048)
			(stroke
				(width 0.1)
				(type default)
			)
			(layer "F.Fab")
		)
		(fp_line
			(start 0.67945 0.3048)
			(end 0.120396 0.3048)
			(stroke
				(width 0.1)
				(type default)
			)
			(layer "F.Fab")
		)
		(pad "1" smd rect
			(at -0.40005 0 180)
			(size 0.4572 0.508)
			(layers "F.Cu" "F.Mask" "F.Paste")
			(net "FAN_0_TACH_IL")
		)
		(pad "2" smd rect
			(at 0.40005 0 180)
			(size 0.4572 0.508)
			(layers "F.Cu" "F.Mask" "F.Paste")
			(net "FAN_0_TACH_IL_R2")
		)
	)
	(footprint ""
		(layer "F.Cu")
		(at 30.226 -124.206 -90)
		(property "Reference" "R4938"
			(at 0 0 270)
			(layer "F.SilkS")
			(hide yes)
			(effects
				(font
					(size 1.27 1.27)
				)
			)
		)
		(property "Value" ""
			(at 0 0 270)
			(layer "F.Fab")
			(effects
				(font
					(size 1.27 1.27)
				)
			)
		)
		(duplicate_pad_numbers_are_jumpers no)
		(fp_line
			(start -0.7874 0.4064)
			(end -0.7874 -0.4064)
			(stroke
				(width 0.1524)
				(type default)
			)
			(layer "F.SilkS")
		)
		(fp_line
			(start 0.7874 0.4064)
			(end -0.7874 0.4064)
			(stroke
				(width 0.1524)
				(type default)
			)
			(layer "F.SilkS")
		)
		(fp_line
			(start -0.7874 -0.4064)
			(end 0.7874 -0.4064)
			(stroke
				(width 0.1524)
				(type default)
			)
			(layer "F.SilkS")
		)
		(fp_line
			(start 0.7874 -0.4064)
			(end 0.7874 0.4064)
			(stroke
				(width 0.1524)
				(type default)
			)
			(layer "F.SilkS")
		)
		(fp_line
			(start -0.67945 0.3048)
			(end -0.67945 -0.305054)
			(stroke
				(width 0.1)
				(type default)
			)
			(layer "F.Fab")
		)
		(fp_line
			(start -0.12065 0.3048)
			(end -0.67945 0.3048)
			(stroke
				(width 0.1)
				(type default)
			)
			(layer "F.Fab")
		)
		(fp_line
			(start 0.120396 0.3048)
			(end 0.120396 0.2794)
			(stroke
				(width 0.1)
				(type default)
			)
			(layer "F.Fab")
		)
		(fp_line
			(start 0.67945 0.3048)
			(end 0.120396 0.3048)
			(stroke
				(width 0.1)
				(type default)
			)
			(layer "F.Fab")
		)
		(fp_line
			(start -0.12065 0.2794)
			(end -0.12065 0.3048)
			(stroke
				(width 0.1)
				(type default)
			)
			(layer "F.Fab")
		)
		(fp_line
			(start 0.120396 0.2794)
			(end -0.12065 0.2794)
			(stroke
				(width 0.1)
				(type default)
			)
			(layer "F.Fab")
		)
		(fp_line
			(start -0.12065 -0.2794)
			(end 0.12065 -0.2794)
			(stroke
				(width 0.1)
				(type default)
			)
			(layer "F.Fab")
		)
		(fp_line
			(start 0.12065 -0.2794)
			(end 0.12065 -0.3048)
			(stroke
				(width 0.1)
				(type default)
			)
			(layer "F.Fab")
		)
		(fp_line
			(start 0.12065 -0.3048)
			(end 0.67945 -0.3048)
			(stroke
				(width 0.1)
				(type default)
			)
			(layer "F.Fab")
		)
		(fp_line
			(start 0.67945 -0.3048)
			(end 0.67945 0.3048)
			(stroke
				(width 0.1)
				(type default)
			)
			(layer "F.Fab")
		)
		(fp_line
			(start -0.67945 -0.305054)
			(end -0.12065 -0.305054)
			(stroke
				(width 0.1)
				(type default)
			)
			(layer "F.Fab")
		)
		(fp_line
			(start -0.12065 -0.305054)
			(end -0.12065 -0.2794)
			(stroke
				(width 0.1)
				(type default)
			)
			(layer "F.Fab")
		)
		(pad "1" smd circle
			(at -0.40005 0 270)
			(size 0 0)
			(layers "F.Cu" "F.Mask" "F.Paste")
			(net "MAX31790_U317_SPIN_START")
		)
		(pad "2" smd circle
			(at 0.40005 0 270)
			(size 0 0)
			(layers "F.Cu" "F.Mask" "F.Paste")
			(net "P3V3_AUX")
		)
	)
)
